FILE_TYPE = CONNECTIVITY;
{Allegro Design Entry HDL 16.6-p007 (v16-6-112F) 10/10/2012}
"PAGE_NUMBER" = 87;
0"NC";
1"M_M_DQS_DN<17:0>";
2"M_M_DQS_DP<17:0>";
3"M_M_MA<17:0>";
4"M_M_DQ<63:0>";
5"M_M_CLK_DN<3:0>";
6"M_M_CLK_DP<3:0>";
7"M_M_CS_N<7:0>";
8"M_M_ECC<7:0>";
9"M_M_CKE<3:0>";
10"M_M_BG<1:0>";
11"M_M_BA<1:0>";
12"M_M_ODT<3:0>";
13"PVDDQ_KLM\g";
14"GND\g";
15"GND\g";
16"GND\g";
17"PVPP_KLM\g";
18"PVPP_KLM\g";
19"P12V_NVDIMM_KLM\g";
20"GND\g";
21"PVTT_KLM\g";
22"M_M_VREF";
23"TP_CH_M_DIMM_M0_RFU_1";
24"TP_CH_M_DIMM_M0_RFU_0";
25"TP_CH_M_DIMM_M0_RFU_2";
26"SMB_DDR_KLM_VPP_SDA";
27"SMB_DDR_KLM_VPP_SCL";
28"FM_ADR_COMPLETE_KLM_N";
29"M_KLM_RST_N";
30"M_M_PAR";
31"FM_DIMM_EVENT_COD_N";
32"M_M_C<2>";
33"M_M_CS_N<0>";
34"M_M_CKE<0>";
35"M_M_ODT<1>";
36"M_M_ODT<0>";
37"M_M_ECC<6>";
38"M_M_BA<0>";
39"M_M_BG<1>";
40"M_M_BG<0>";
41"M_M_CLK_DP<1>";
42"M_M_CKE<1>";
43"M_M_ECC<1>";
44"M_M_ECC<0>";
45"M_M_ECC<3>";
46"M_M_ECC<2>";
47"M_M_ECC<5>";
48"M_M_ECC<4>";
49"M_M_ECC<7>";
50"M_M_MA<0>";
51"M_M_CS_N<1>";
52"M_M_CS_N<2>";
53"M_M_BA<1>";
54"M_M_CLK_DN<0>";
55"M_M_CLK_DP<0>";
56"M_M_CLK_DN<1>";
57"M_M_CS_N<3>";
58"M_M_ALERT_N";
59"M_M_ACT_N";
60"M_M_DQ<1>";
61"M_M_DQ<4>";
62"M_M_DQ<5>";
63"M_M_DQ<2>";
64"M_M_DQ<3>";
65"M_M_DQ<0>";
66"M_M_DQ<7>";
67"M_M_DQ<6>";
68"M_M_DQ<9>";
69"M_M_DQ<8>";
70"M_M_DQ<10>";
71"M_M_DQ<11>";
72"M_M_DQ<14>";
73"M_M_DQ<12>";
74"M_M_DQ<15>";
75"M_M_DQ<17>";
76"M_M_DQ<13>";
77"M_M_DQ<16>";
78"M_M_DQ<19>";
79"M_M_DQ<18>";
80"M_M_DQ<21>";
81"M_M_DQ<20>";
82"M_M_DQ<27>";
83"M_M_DQ<23>";
84"M_M_DQ<22>";
85"M_M_DQ<25>";
86"M_M_DQ<24>";
87"M_M_DQ<26>";
88"M_M_DQ<31>";
89"M_M_DQ<30>";
90"M_M_DQ<29>";
91"M_M_DQ<28>";
92"M_M_DQ<37>";
93"M_M_DQ<34>";
94"M_M_DQ<33>";
95"M_M_DQ<32>";
96"M_M_DQ<35>";
97"M_M_DQ<39>";
98"M_M_DQ<36>";
99"M_M_DQ<38>";
100"M_M_DQ<41>";
101"M_M_DQ<40>";
102"M_M_DQ<43>";
103"M_M_DQ<42>";
104"M_M_DQ<45>";
105"M_M_DQ<44>";
106"M_M_DQ<47>";
107"M_M_MA<16>";
108"M_M_MA<15>";
109"M_M_MA<14>";
110"M_M_MA<11>";
111"M_M_MA<10>";
112"M_M_MA<2>";
113"M_M_MA<9>";
114"M_M_MA<8>";
115"M_M_MA<7>";
116"M_M_MA<6>";
117"M_M_MA<5>";
118"M_M_MA<4>";
119"M_M_MA<3>";
120"M_M_MA<17>";
121"M_M_MA<13>";
122"M_M_MA<12>";
123"M_M_MA<1>";
124"M_M_DQ<46>";
125"M_M_DQ<49>";
126"M_M_DQ<48>";
127"M_M_DQ<51>";
128"M_M_DQ<50>";
129"M_M_DQ<53>";
130"M_M_DQ<52>";
131"M_M_DQ<55>";
132"M_M_DQ<56>";
133"M_M_DQ<54>";
134"M_M_DQ<57>";
135"M_M_DQ<63>";
136"M_M_DQ<60>";
137"M_M_DQ<59>";
138"M_M_DQ<58>";
139"M_M_DQ<61>";
140"M_M_DQ<62>";
141"M_M_DQS_DP<6>";
142"M_M_DQS_DN<6>";
143"M_M_DQS_DP<5>";
144"M_M_DQS_DN<5>";
145"M_M_DQS_DP<4>";
146"M_M_DQS_DN<4>";
147"M_M_DQS_DP<3>";
148"M_M_DQS_DN<3>";
149"M_M_DQS_DP<2>";
150"M_M_DQS_DN<2>";
151"M_M_DQS_DP<1>";
152"M_M_DQS_DN<1>";
153"M_M_DQS_DP<0>";
154"M_M_DQS_DN<0>";
155"M_M_DQS_DP<9>";
156"M_M_DQS_DN<9>";
157"M_M_DQS_DP<8>";
158"M_M_DQS_DN<8>";
159"M_M_DQS_DP<7>";
160"M_M_DQS_DN<7>";
161"M_M_DQS_DN<17>";
162"M_M_DQS_DP<16>";
163"M_M_DQS_DN<16>";
164"M_M_DQS_DP<15>";
165"M_M_DQS_DN<15>";
166"M_M_DQS_DP<14>";
167"M_M_DQS_DN<14>";
168"M_M_DQS_DP<13>";
169"M_M_DQS_DN<13>";
170"M_M_DQS_DP<12>";
171"M_M_DQS_DN<12>";
172"M_M_DQS_DP<11>";
173"M_M_DQS_DN<11>";
174"M_M_DQS_DP<10>";
175"M_M_DQS_DN<10>";
176"M_M_DQS_DP<17>";
%"TAP"
"6","(-1750,2200)","2","mstr_standard","I100";
;
HDL_TAP"TRUE"
BODY_TYPE"PLUMBING"
CDS_LIB"mstr_standard";
"B \NAC \NWC"4;
"S \NAC"
BN"8"69;
%"TAP"
"6","(-1750,2300)","2","mstr_standard","I101";
;
HDL_TAP"TRUE"
BODY_TYPE"PLUMBING"
CDS_LIB"mstr_standard";
"B \NAC \NWC"4;
"S \NAC"
BN"10"70;
%"TAP"
"6","(-1750,2350)","2","mstr_standard","I102";
;
HDL_TAP"TRUE"
BODY_TYPE"PLUMBING"
CDS_LIB"mstr_standard";
"B \NAC \NWC"4;
"S \NAC"
BN"13"76;
%"TAP"
"6","(-1750,2100)","2","mstr_standard","I103";
;
HDL_TAP"TRUE"
BODY_TYPE"PLUMBING"
CDS_LIB"mstr_standard";
"B \NAC \NWC"4;
"S \NAC"
BN"6"67;
%"TAP"
"6","(-1750,2050)","2","mstr_standard","I104";
;
HDL_TAP"TRUE"
BODY_TYPE"PLUMBING"
CDS_LIB"mstr_standard";
"B \NAC \NWC"4;
"S \NAC"
BN"7"66;
%"TAP"
"6","(-1750,2000)","2","mstr_standard","I105";
;
HDL_TAP"TRUE"
BODY_TYPE"PLUMBING"
CDS_LIB"mstr_standard";
"B \NAC \NWC"4;
"S \NAC"
BN"4"61;
%"TAP"
"6","(-1750,1950)","2","mstr_standard","I106";
;
HDL_TAP"TRUE"
BODY_TYPE"PLUMBING"
CDS_LIB"mstr_standard";
"B \NAC \NWC"4;
"S \NAC"
BN"5"62;
%"TAP"
"6","(-1750,1900)","2","mstr_standard","I107";
;
HDL_TAP"TRUE"
BODY_TYPE"PLUMBING"
CDS_LIB"mstr_standard";
"B \NAC \NWC"4;
"S \NAC"
BN"2"63;
%"TAP"
"6","(-1750,1750)","2","mstr_standard","I108";
;
HDL_TAP"TRUE"
BODY_TYPE"PLUMBING"
CDS_LIB"mstr_standard";
"B \NAC \NWC"4;
"S \NAC"
BN"1"60;
%"TAP"
"6","(-1750,1850)","2","mstr_standard","I109";
;
HDL_TAP"TRUE"
BODY_TYPE"PLUMBING"
CDS_LIB"mstr_standard";
"B \NAC \NWC"4;
"S \NAC"
BN"3"64;
%"PVDDQ_KLM"
"1","(-1450,2600)","0","mstr_symbols","I11";
;
HDL_POWER"PVDDQ_KLM"
ROOM"DDR4_CH_D"
BODY_TYPE"PLUMBING"
CDS_LIB"mstr_symbols"
BOM_COST"MEM"
VOLTAGE"1.2V";
"G\NAC"13;
%"TAP"
"6","(-1750,1800)","2","mstr_standard","I110";
;
HDL_TAP"TRUE"
BODY_TYPE"PLUMBING"
CDS_LIB"mstr_standard";
"B \NAC \NWC"4;
"S \NAC"
BN"0"65;
%"TAP"
"6","(-3250,4850)","0","mstr_standard","I112";
;
HDL_TAP"TRUE"
BODY_TYPE"PLUMBING"
CDS_LIB"mstr_standard";
"B \NAC \NWC"3;
"S \NAC"
BN"16"107;
%"TAP"
"6","(-3250,4900)","0","mstr_standard","I113";
;
HDL_TAP"TRUE"
BODY_TYPE"PLUMBING"
CDS_LIB"mstr_standard";
"B \NAC \NWC"3;
"S \NAC"
BN"17"120;
%"TAP"
"6","(-3250,4800)","0","mstr_standard","I114";
;
HDL_TAP"TRUE"
BODY_TYPE"PLUMBING"
CDS_LIB"mstr_standard";
"B \NAC \NWC"3;
"S \NAC"
BN"15"108;
%"TAP"
"6","(-3250,4750)","0","mstr_standard","I115";
;
HDL_TAP"TRUE"
BODY_TYPE"PLUMBING"
CDS_LIB"mstr_standard";
"B \NAC \NWC"3;
"S \NAC"
BN"14"109;
%"TAP"
"6","(-3250,4700)","0","mstr_standard","I116";
;
HDL_TAP"TRUE"
BODY_TYPE"PLUMBING"
CDS_LIB"mstr_standard";
"B \NAC \NWC"3;
"S \NAC"
BN"13"121;
%"TAP"
"6","(-3250,4650)","0","mstr_standard","I117";
;
HDL_TAP"TRUE"
BODY_TYPE"PLUMBING"
CDS_LIB"mstr_standard";
"B \NAC \NWC"3;
"S \NAC"
BN"12"122;
%"TAP"
"6","(-3250,4600)","0","mstr_standard","I118";
;
HDL_TAP"TRUE"
BODY_TYPE"PLUMBING"
CDS_LIB"mstr_standard";
"B \NAC \NWC"3;
"S \NAC"
BN"11"110;
%"TAP"
"6","(-3250,4550)","0","mstr_standard","I119";
;
HDL_TAP"TRUE"
BODY_TYPE"PLUMBING"
CDS_LIB"mstr_standard";
"B \NAC \NWC"3;
"S \NAC"
BN"10"111;
%"TAP"
"6","(900,4500)","2","mstr_standard","I12";
;
HDL_TAP"TRUE"
BODY_TYPE"PLUMBING"
CDS_LIB"mstr_standard";
"B \NAC \NWC"1;
"S \NAC"
BN"11"173;
%"TAP"
"6","(-3250,4450)","0","mstr_standard","I120";
;
HDL_TAP"TRUE"
BODY_TYPE"PLUMBING"
CDS_LIB"mstr_standard";
"B \NAC \NWC"3;
"S \NAC"
BN"8"114;
%"TAP"
"6","(-3250,4500)","0","mstr_standard","I121";
;
HDL_TAP"TRUE"
BODY_TYPE"PLUMBING"
CDS_LIB"mstr_standard";
"B \NAC \NWC"3;
"S \NAC"
BN"9"113;
%"TAP"
"6","(-3250,4400)","0","mstr_standard","I122";
;
HDL_TAP"TRUE"
BODY_TYPE"PLUMBING"
CDS_LIB"mstr_standard";
"B \NAC \NWC"3;
"S \NAC"
BN"7"115;
%"TAP"
"6","(-3250,4350)","0","mstr_standard","I123";
;
HDL_TAP"TRUE"
BODY_TYPE"PLUMBING"
CDS_LIB"mstr_standard";
"B \NAC \NWC"3;
"S \NAC"
BN"6"116;
%"TAP"
"6","(-3250,4300)","0","mstr_standard","I124";
;
HDL_TAP"TRUE"
BODY_TYPE"PLUMBING"
CDS_LIB"mstr_standard";
"B \NAC \NWC"3;
"S \NAC"
BN"5"117;
%"TAP"
"6","(-3250,4250)","0","mstr_standard","I125";
;
HDL_TAP"TRUE"
BODY_TYPE"PLUMBING"
CDS_LIB"mstr_standard";
"B \NAC \NWC"3;
"S \NAC"
BN"4"118;
%"TAP"
"6","(-3250,4200)","0","mstr_standard","I126";
;
HDL_TAP"TRUE"
BODY_TYPE"PLUMBING"
CDS_LIB"mstr_standard";
"B \NAC \NWC"3;
"S \NAC"
BN"3"119;
%"TAP"
"6","(-3250,4150)","0","mstr_standard","I127";
;
HDL_TAP"TRUE"
BODY_TYPE"PLUMBING"
CDS_LIB"mstr_standard";
"B \NAC \NWC"3;
"S \NAC"
BN"2"112;
%"TAP"
"6","(-3250,4100)","0","mstr_standard","I128";
;
HDL_TAP"TRUE"
BODY_TYPE"PLUMBING"
CDS_LIB"mstr_standard";
"B \NAC \NWC"3;
"S \NAC"
BN"1"123;
%"TAP"
"6","(-3250,4050)","0","mstr_standard","I129";
;
HDL_TAP"TRUE"
BODY_TYPE"PLUMBING"
CDS_LIB"mstr_standard";
"B \NAC \NWC"3;
"S \NAC"
BN"0"50;
%"TAP"
"6","(900,4400)","2","mstr_standard","I13";
;
HDL_TAP"TRUE"
BODY_TYPE"PLUMBING"
CDS_LIB"mstr_standard";
"B \NAC \NWC"1;
"S \NAC"
BN"10"175;
%"TAP"
"6","(-3250,3950)","0","mstr_standard","I130";
;
HDL_TAP"TRUE"
BODY_TYPE"PLUMBING"
CDS_LIB"mstr_standard";
"B \NAC \NWC"11;
"S \NAC"
BN"1"53;
%"TAP"
"6","(-3250,3900)","0","mstr_standard","I133";
;
HDL_TAP"TRUE"
BODY_TYPE"PLUMBING"
CDS_LIB"mstr_standard";
"B \NAC \NWC"11;
"S \NAC"
BN"0"38;
%"TAP"
"6","(-3250,3800)","0","mstr_standard","I134";
;
HDL_TAP"TRUE"
BODY_TYPE"PLUMBING"
CDS_LIB"mstr_standard";
"B \NAC \NWC"10;
"S \NAC"
BN"0"40;
%"TAP"
"6","(-3250,3850)","0","mstr_standard","I135";
;
HDL_TAP"TRUE"
BODY_TYPE"PLUMBING"
CDS_LIB"mstr_standard";
"B \NAC \NWC"10;
"S \NAC"
BN"1"39;
%"TAP"
"6","(-3250,2800)","0","mstr_standard","I138";
;
HDL_TAP"TRUE"
BODY_TYPE"PLUMBING"
CDS_LIB"mstr_standard";
"B \NAC \NWC"8;
"S \NAC"
BN"7"49;
%"TAP"
"6","(-3250,2850)","0","mstr_standard","I139";
;
HDL_TAP"TRUE"
BODY_TYPE"PLUMBING"
CDS_LIB"mstr_standard";
"B \NAC \NWC"8;
"S \NAC"
BN"6"37;
%"TAP"
"6","(900,4300)","2","mstr_standard","I14";
;
HDL_TAP"TRUE"
BODY_TYPE"PLUMBING"
CDS_LIB"mstr_standard";
"B \NAC \NWC"1;
"S \NAC"
BN"9"156;
%"TAP"
"6","(-3250,2750)","0","mstr_standard","I140";
;
HDL_TAP"TRUE"
BODY_TYPE"PLUMBING"
CDS_LIB"mstr_standard";
"B \NAC \NWC"8;
"S \NAC"
BN"4"48;
%"TAP"
"6","(-3250,2700)","0","mstr_standard","I141";
;
HDL_TAP"TRUE"
BODY_TYPE"PLUMBING"
CDS_LIB"mstr_standard";
"B \NAC \NWC"8;
"S \NAC"
BN"5"47;
%"TAP"
"6","(-3250,2650)","0","mstr_standard","I142";
;
HDL_TAP"TRUE"
BODY_TYPE"PLUMBING"
CDS_LIB"mstr_standard";
"B \NAC \NWC"8;
"S \NAC"
BN"2"46;
%"TAP"
"6","(-3250,2600)","0","mstr_standard","I143";
;
HDL_TAP"TRUE"
BODY_TYPE"PLUMBING"
CDS_LIB"mstr_standard";
"B \NAC \NWC"8;
"S \NAC"
BN"3"45;
%"TAP"
"6","(-3250,2550)","0","mstr_standard","I144";
;
HDL_TAP"TRUE"
BODY_TYPE"PLUMBING"
CDS_LIB"mstr_standard";
"B \NAC \NWC"8;
"S \NAC"
BN"0"44;
%"TAP"
"6","(-3250,2500)","0","mstr_standard","I145";
;
HDL_TAP"TRUE"
BODY_TYPE"PLUMBING"
CDS_LIB"mstr_standard";
"B \NAC \NWC"8;
"S \NAC"
BN"1"43;
%"TAP"
"6","(900,4200)","2","mstr_standard","I15";
;
HDL_TAP"TRUE"
BODY_TYPE"PLUMBING"
CDS_LIB"mstr_standard";
"B \NAC \NWC"1;
"S \NAC"
BN"8"158;
%"TAP"
"6","(-3250,3700)","0","mstr_standard","I152";
;
HDL_TAP"TRUE"
BODY_TYPE"PLUMBING"
CDS_LIB"mstr_standard";
"B \NAC \NWC"6;
"S \NAC"
BN"1"41;
%"TAP"
"6","(-3250,3600)","0","mstr_standard","I153";
;
HDL_TAP"TRUE"
BODY_TYPE"PLUMBING"
CDS_LIB"mstr_standard";
"B \NAC \NWC"6;
"S \NAC"
BN"0"55;
%"TAP"
"6","(-3450,3650)","0","mstr_standard","I154";
;
HDL_TAP"TRUE"
BODY_TYPE"PLUMBING"
CDS_LIB"mstr_standard";
"B \NAC \NWC"5;
"S \NAC"
BN"1"56;
%"TAP"
"6","(-3450,3550)","0","mstr_standard","I155";
;
HDL_TAP"TRUE"
BODY_TYPE"PLUMBING"
CDS_LIB"mstr_standard";
"B \NAC \NWC"5;
"S \NAC"
BN"0"54;
%"TAP"
"6","(-3250,3400)","0","mstr_standard","I158";
;
HDL_TAP"TRUE"
BODY_TYPE"PLUMBING"
CDS_LIB"mstr_standard";
"B \NAC \NWC"7;
"S \NAC"
BN"3"57;
%"TAP"
"6","(-3250,3350)","0","mstr_standard","I159";
;
HDL_TAP"TRUE"
BODY_TYPE"PLUMBING"
CDS_LIB"mstr_standard";
"B \NAC \NWC"7;
"S \NAC"
BN"2"52;
%"TAP"
"6","(900,4100)","2","mstr_standard","I16";
;
HDL_TAP"TRUE"
BODY_TYPE"PLUMBING"
CDS_LIB"mstr_standard";
"B \NAC \NWC"1;
"S \NAC"
BN"7"160;
%"TAP"
"6","(-3250,3300)","0","mstr_standard","I160";
;
HDL_TAP"TRUE"
BODY_TYPE"PLUMBING"
CDS_LIB"mstr_standard";
"B \NAC \NWC"7;
"S \NAC"
BN"1"51;
%"TAP"
"6","(-3250,3250)","0","mstr_standard","I161";
;
HDL_TAP"TRUE"
BODY_TYPE"PLUMBING"
CDS_LIB"mstr_standard";
"B \NAC \NWC"7;
"S \NAC"
BN"0"33;
%"TAP"
"6","(-3250,3150)","0","mstr_standard","I163";
;
HDL_TAP"TRUE"
BODY_TYPE"PLUMBING"
CDS_LIB"mstr_standard";
"B \NAC \NWC"9;
"S \NAC"
BN"1"42;
%"TAP"
"6","(-3250,3100)","0","mstr_standard","I164";
;
HDL_TAP"TRUE"
BODY_TYPE"PLUMBING"
CDS_LIB"mstr_standard";
"B \NAC \NWC"9;
"S \NAC"
BN"0"34;
%"TAP"
"6","(-3250,3000)","0","mstr_standard","I165";
;
HDL_TAP"TRUE"
BODY_TYPE"PLUMBING"
CDS_LIB"mstr_standard";
"B \NAC \NWC"12;
"S \NAC"
BN"1"35;
%"TAP"
"6","(-3250,2950)","0","mstr_standard","I166";
;
HDL_TAP"TRUE"
BODY_TYPE"PLUMBING"
CDS_LIB"mstr_standard";
"B \NAC \NWC"12;
"S \NAC"
BN"0"36;
%"SCONN288_H44441004"
"4","(-400,2050)","0","mstr_sconn","I169";
;
CDS_SEC"4"
ROOM"DDR4_CH_M"
CDS_LOCATION"J1A1"
SEC"4"
SEC_TYPE"PIP"
CDS_LIB"mstr_sconn"
BOM_COST"MEM"
PACK_TYPE"PIP"
MATERIAL"SCONN"
PART_NUMBER"H44441-004"
LOCATION"J1A1";
"VPP<4>"
$PN"142"17;
"VTT<1>"
$PN"77"21;
"VPP<0>"
$PN"287"17;
"VPP<1>"
$PN"286"17;
"VPP<2>"
$PN"288"17;
"VPP<3>"
$PN"143"17;
"VDD<1>"
$PN"233"13;
"VDD<2>"
$PN"231"13;
"VDD<3>"
$PN"229"13;
"VDD<4>"
$PN"226"13;
"VDD<5>"
$PN"223"13;
"VDD<7>"
$PN"217"13;
"VDD<8>"
$PN"215"13;
"VDD<9>"
$PN"212"13;
"VDD<11>"
$PN"206"13;
"VDD<12>"
$PN"204"13;
"VDD<14>"
$PN"90"13;
"VDD<15>"
$PN"88"13;
"VDD<17>"
$PN"83"13;
"VDD<18>"
$PN"80"13;
"VDD<20>"
$PN"73"13;
"VDD<21>"
$PN"70"13;
"VDD<22>"
$PN"67"13;
"VDD<24>"
$PN"61"13;
"12V<0>"
$PN"145"19;
"12V<1>"
$PN"1"19;
"VTT<0>"
$PN"221"21;
"VDD<25>"
$PN"59"13;
"VDD<23>"
$PN"64"13;
"VDD<19>"
$PN"76"13;
"VDD<16>"
$PN"85"13;
"VDD<13>"
$PN"92"13;
"VDD<10>"
$PN"209"13;
"VDD<6>"
$PN"220"13;
"VDD<0>"
$PN"236"13;
%"TAP"
"6","(900,4000)","2","mstr_standard","I17";
;
HDL_TAP"TRUE"
BODY_TYPE"PLUMBING"
CDS_LIB"mstr_standard";
"B \NAC \NWC"1;
"S \NAC"
BN"6"142;
%"GND"
"1","(2500,1150)","2","mstr_symbols","I170";
;
HDL_POWER"GND"
ROOM"DDR4_CH_D"
BODY_TYPE"PLUMBING"
SIZE"1B"
CDS_LIB"mstr_symbols"
BOM_COST"MEM"
VOLTAGE"0";
"A\NAC"14;
%"GND"
"1","(-5000,1850)","2","mstr_symbols","I176";
;
HDL_POWER"GND"
ROOM"DDR4_CH_D"
BODY_TYPE"PLUMBING"
SIZE"1B"
CDS_LIB"mstr_symbols"
BOM_COST"MEM"
VOLTAGE"0";
"A\NAC"15;
%"GND"
"1","(-4650,1300)","0","mstr_symbols","I177";
;
HDL_POWER"GND"
ROOM"DDR4_CH_M1"
BODY_TYPE"PLUMBING"
SIZE"1B"
BOM_COST"MEM"
CDS_LIB"mstr_symbols"
VOLTAGE"16V";
"A\NAC"16;
%"CAP_A"
"1","(-4650,1550)","2","dev_discrete","I178";
;
ROOM"DDR4_CH_M"
SEC"1"
SEC_TYPE"0402V"
CDS_SEC"1"
CDS_LIB"dev_discrete"
BOM_COST"MEM"
CDS_LOCATION"C1A5"
MATERIAL"X7R"
VOLTAGE"25V"
PACK_TYPE"0402V"
TOLERANCE"10%"
VALUE"0.01UF"
PART_NUMBER"A36096-045"
LOCATION"C1A5";
"B"
$PN"2"16;
"A"
$PN"1"22;
%"PVPP_KLM"
"1","(-1100,3050)","0","mstr_symbols","I179";
;
HDL_POWER"PVPP_KLM"
ROOM"DDR4_CH_D"
BODY_TYPE"PLUMBING"
CDS_LIB"mstr_symbols"
BOM_COST"MEM"
VOLTAGE"2.5V";
"G\NAC"17;
%"TAP"
"6","(900,3900)","2","mstr_standard","I18";
;
HDL_TAP"TRUE"
BODY_TYPE"PLUMBING"
CDS_LIB"mstr_standard";
"B \NAC \NWC"1;
"S \NAC"
BN"5"144;
%"PVPP_KLM"
"1","(-5000,2250)","0","mstr_symbols","I180";
;
HDL_POWER"PVPP_KLM"
ROOM"DDR4_CH_D"
BODY_TYPE"PLUMBING"
CDS_LIB"mstr_symbols"
BOM_COST"MEM"
VOLTAGE"2.5V";
"G\NAC"18;
%"SCONN288_H44441004"
"3","(1800,2450)","0","mstr_sconn","I185";
;
CDS_SEC"3"
ROOM"DDR4_CH_M"
CDS_LOCATION"J1A1"
SEC"3"
SEC_TYPE"PIP"
CDS_LIB"mstr_sconn"
BOM_COST"MEM"
PACK_TYPE"PIP"
MATERIAL"SCONN"
PART_NUMBER"H44441-004"
LOCATION"J1A1";
"VSS<93>"
$PN"2"20;
"VSS<92>"
$PN"4"20;
"VSS<91>"
$PN"6"20;
"VSS<90>"
$PN"9"20;
"VSS<89>"
$PN"11"20;
"VSS<88>"
$PN"13"20;
"VSS<0>"
$PN"283"14;
"VSS<1>"
$PN"281"14;
"VSS<2>"
$PN"279"14;
"VSS<3>"
$PN"276"14;
"VSS<4>"
$PN"274"14;
"VSS<5>"
$PN"272"14;
"VSS<6>"
$PN"270"14;
"VSS<7>"
$PN"268"14;
"VSS<8>"
$PN"265"14;
"VSS<9>"
$PN"263"14;
"VSS<10>"
$PN"261"14;
"VSS<11>"
$PN"259"14;
"VSS<12>"
$PN"257"14;
"VSS<13>"
$PN"254"14;
"VSS<14>"
$PN"252"14;
"VSS<15>"
$PN"250"14;
"VSS<16>"
$PN"248"14;
"VSS<17>"
$PN"246"14;
"VSS<18>"
$PN"243"14;
"VSS<19>"
$PN"241"14;
"VSS<20>"
$PN"239"14;
"VSS<21>"
$PN"202"14;
"VSS<22>"
$PN"200"14;
"VSS<23>"
$PN"198"14;
"VSS<24>"
$PN"195"14;
"VSS<25>"
$PN"193"14;
"VSS<26>"
$PN"191"14;
"VSS<27>"
$PN"189"14;
"VSS<28>"
$PN"187"14;
"VSS<29>"
$PN"184"14;
"VSS<30>"
$PN"182"14;
"VSS<31>"
$PN"180"14;
"VSS<32>"
$PN"178"14;
"VSS<33>"
$PN"176"14;
"VSS<34>"
$PN"173"14;
"VSS<35>"
$PN"171"14;
"VSS<36>"
$PN"169"14;
"VSS<37>"
$PN"167"14;
"VSS<38>"
$PN"165"14;
"VSS<39>"
$PN"162"14;
"VSS<40>"
$PN"160"14;
"VSS<41>"
$PN"158"14;
"VSS<42>"
$PN"156"14;
"VSS<43>"
$PN"154"14;
"VSS<44>"
$PN"151"14;
"VSS<47>"
$PN"138"20;
"VSS<48>"
$PN"136"20;
"VSS<49>"
$PN"134"20;
"VSS<50>"
$PN"131"20;
"VSS<51>"
$PN"129"20;
"VSS<52>"
$PN"127"20;
"VSS<53>"
$PN"125"20;
"VSS<54>"
$PN"123"20;
"VSS<55>"
$PN"120"20;
"VSS<56>"
$PN"118"20;
"VSS<57>"
$PN"116"20;
"VSS<58>"
$PN"114"20;
"VSS<59>"
$PN"112"20;
"VSS<60>"
$PN"109"20;
"VSS<61>"
$PN"107"20;
"VSS<62>"
$PN"105"20;
"VSS<63>"
$PN"103"20;
"VSS<64>"
$PN"101"20;
"VSS<65>"
$PN"98"20;
"VSS<66>"
$PN"96"20;
"VSS<67>"
$PN"94"20;
"VSS<68>"
$PN"57"20;
"VSS<69>"
$PN"55"20;
"VSS<70>"
$PN"53"20;
"VSS<71>"
$PN"50"20;
"VSS<72>"
$PN"48"20;
"VSS<73>"
$PN"46"20;
"VSS<74>"
$PN"44"20;
"VSS<75>"
$PN"42"20;
"VSS<76>"
$PN"39"20;
"VSS<77>"
$PN"37"20;
"VSS<78>"
$PN"35"20;
"VSS<79>"
$PN"33"20;
"VSS<80>"
$PN"31"20;
"VSS<81>"
$PN"28"20;
"VSS<82>"
$PN"26"20;
"VSS<83>"
$PN"24"20;
"VSS<84>"
$PN"22"20;
"VSS<85>"
$PN"20"20;
"VSS<86>"
$PN"17"20;
"VSS<87>"
$PN"15"20;
"VSS<45>"
$PN"149"14;
"VSS<46>"
$PN"147"14;
%"SCONN288_H44441004"
"1","(-2500,3250)","0","mstr_sconn","I186";
;
CDS_SEC"1"
ROOM"DDR4_CH_M"
CDS_LOCATION"J1A1"
SEC"1"
SEC_TYPE"PIP"
CDS_LIB"mstr_sconn"
BOM_COST"MEM"
PACK_TYPE"PIP"
MATERIAL"SCONN"
PART_NUMBER"H44441-004"
LOCATION"J1A1";
"DQ<63>"
$PN"280"140;
"DQ<62>"
$PN"135"135;
"DQ<61>"
$PN"273"136;
"DQ<5>"
$PN"148"61;
"DQ<4>"
$PN"3"62;
"DQ<3>"
$PN"157"63;
"DQ<2>"
$PN"12"64;
"DQ<47>"
$PN"258"124;
"DQ<48>"
$PN"119"125;
"DQ<49>"
$PN"264"126;
"DQ<50>"
$PN"126"127;
"DQ<51>"
$PN"271"128;
"DQ<52>"
$PN"117"129;
"DQ<53>"
$PN"262"130;
"DQ<54>"
$PN"124"131;
"DQ<58>"
$PN"137"137;
"DQ<57>"
$PN"275"132;
"SAVE_N_NC"
$PN"230"28;
"RFU<1>"
$PN"227"23;
"RFU<0>"
$PN"205"24;
"DQ<17>"
$PN"172"77;
"DQ<15>"
$PN"166"72;
"DQ<26>"
$PN"45"82;
"DQ<27>"
$PN"190"87;
"S0_N"
$PN"84"33;
"CKE<0>"
$PN"60"34;
"ODT<1>"
$PN"91"35;
"ODT<0>"
$PN"87"36;
"CB<7>"
$PN"199"37;
"A16_RAS_N"
$PN"82"107;
"A15_CAS_N"
$PN"86"108;
"A14_WE_N"
$PN"228"109;
"A11"
$PN"210"110;
"A10"
$PN"225"111;
"DQ<38>"
$PN"102"97;
"DQ<36>"
$PN"95"92;
"DQ<35>"
$PN"249"93;
"A2"
$PN"216"112;
"ALERT_N"
$PN"208"58;
"ACT_N"
$PN"62"59;
"DQ<0>"
$PN"5"60;
"DQ<1>"
$PN"150"65;
"SA<1>"
$PN"140"15;
"SA<2>"
$PN"238"18;
"VDDSPD"
$PN"284"18;
"SA<0>"
$PN"139"15;
"BA<0>"
$PN"81"38;
"BG<1>"
$PN"207"39;
"BG<0>"
$PN"63"40;
"CK1P"
$PN"218"41;
"VREFCA"
$PN"146"22;
"SDA"
$PN"285"26;
"SCL"
$PN"141"27;
"RFU<2>"
$PN"144"25;
"RESET_N"
$PN"58"29;
"PAR"
$PN"222"30;
"EVENT_N"
$PN"78"31;
"DQ<6>"
$PN"10"66;
"DQ<7>"
$PN"155"67;
"DQ<8>"
$PN"16"68;
"DQ<9>"
$PN"161"69;
"DQ<10>"
$PN"23"71;
"DQ<11>"
$PN"168"70;
"DQ<12>"
$PN"14"76;
"DQ<13>"
$PN"159"73;
"DQ<14>"
$PN"21"74;
"DQ<16>"
$PN"27"75;
"DQ<18>"
$PN"34"78;
"DQ<19>"
$PN"179"79;
"DQ<20>"
$PN"25"80;
"DQ<21>"
$PN"170"81;
"DQ<22>"
$PN"32"83;
"DQ<23>"
$PN"177"84;
"DQ<24>"
$PN"38"85;
"DQ<25>"
$PN"183"86;
"DQ<30>"
$PN"43"88;
"DQ<31>"
$PN"188"89;
"DQ<32>"
$PN"97"94;
"DQ<33>"
$PN"242"95;
"DQ<34>"
$PN"104"96;
"DQ<37>"
$PN"240"98;
"DQ<39>"
$PN"247"99;
"DQ<40>"
$PN"108"100;
"DQ<41>"
$PN"253"101;
"DQ<42>"
$PN"115"102;
"DQ<43>"
$PN"260"103;
"DQ<44>"
$PN"106"104;
"DQ<45>"
$PN"251"105;
"DQ<46>"
$PN"113"106;
"DQ<55>"
$PN"269"133;
"DQ<56>"
$PN"130"134;
"DQ<59>"
$PN"282"138;
"DQ<60>"
$PN"128"139;
"CKE<1>"
$PN"203"42;
"CK0N"
$PN"75"54;
"CB<0>"
$PN"49"43;
"CB<1>"
$PN"194"44;
"CB<2>"
$PN"56"45;
"CB<3>"
$PN"201"46;
"CB<4>"
$PN"47"47;
"CB<5>"
$PN"192"48;
"CB<6>"
$PN"54"49;
"A9"
$PN"66"113;
"A8"
$PN"68"114;
"A7"
$PN"211"115;
"A6"
$PN"69"116;
"A5"
$PN"213"117;
"A4"
$PN"214"118;
"A3"
$PN"71"119;
"A17"
$PN"234"120;
"A13"
$PN"232"121;
"A12"
$PN"65"122;
"A1"
$PN"72"123;
"A0"
$PN"79"50;
"C<2>"
$PN"235"32;
"DQ<28>"
$PN"36"90;
"DQ<29>"
$PN"181"91;
"S1_N"
$PN"89"51;
"S2_N_C<0>"
$PN"93"52;
"S3_N_C<1>"
$PN"237"57;
"CK0P"
$PN"74"55;
"CK1N"
$PN"219"56;
"BA<1>"
$PN"224"53;
%"SCONN288_H44441004"
"2","(0,4300)","0","mstr_sconn","I187";
;
CDS_SEC"2"
ROOM"DDR4_CH_M"
CDS_LOCATION"J1A1"
SEC"2"
SEC_TYPE"PIP"
CDS_LIB"mstr_sconn"
BOM_COST"MEM"
PACK_TYPE"PIP"
MATERIAL"SCONN"
PART_NUMBER"H44441-004"
LOCATION"J1A1";
"DQS17P"
$PN"51"176;
"DQS9P"
$PN"7"155;
"DQS9N"
$PN"8"156;
"DQS8P"
$PN"197"157;
"DQS8N"
$PN"196"158;
"DQS7P"
$PN"278"159;
"DQS7N"
$PN"277"160;
"DQS6P"
$PN"267"141;
"DQS6N"
$PN"266"142;
"DQS5P"
$PN"256"143;
"DQS5N"
$PN"255"144;
"DQS4P"
$PN"245"145;
"DQS4N"
$PN"244"146;
"DQS3P"
$PN"186"147;
"DQS3N"
$PN"185"148;
"DQS2P"
$PN"175"149;
"DQS2N"
$PN"174"150;
"DQS1P"
$PN"164"151;
"DQS1N"
$PN"163"152;
"DQS17N"
$PN"52"161;
"DQS16P"
$PN"132"162;
"DQS16N"
$PN"133"163;
"DQS15P"
$PN"121"164;
"DQS15N"
$PN"122"165;
"DQS14P"
$PN"110"166;
"DQS14N"
$PN"111"167;
"DQS13P"
$PN"99"168;
"DQS13N"
$PN"100"169;
"DQS12P"
$PN"40"170;
"DQS12N"
$PN"41"171;
"DQS11P"
$PN"29"172;
"DQS11N"
$PN"30"173;
"DQS10P"
$PN"18"174;
"DQS10N"
$PN"19"175;
"DQS0P"
$PN"153"153;
"DQS0N"
$PN"152"154;
%"P12V_NVDIMM_KLM"
"1","(300,3025)","0","mstr_symbols","I188";
;
HDL_POWER"P12V_NVDIMM_KLM"
BODY_TYPE"PLUMBING"
CDS_LIB"mstr_symbols"
VOLTAGE"12.0";
"G\NAC"19;
%"TAP"
"6","(900,3800)","2","mstr_standard","I19";
;
HDL_TAP"TRUE"
BODY_TYPE"PLUMBING"
CDS_LIB"mstr_standard";
"B \NAC \NWC"1;
"S \NAC"
BN"4"146;
%"TAP"
"6","(900,3700)","2","mstr_standard","I20";
;
HDL_TAP"TRUE"
BODY_TYPE"PLUMBING"
CDS_LIB"mstr_standard";
"B \NAC \NWC"1;
"S \NAC"
BN"3"148;
%"TAP"
"6","(900,3500)","2","mstr_standard","I21";
;
HDL_TAP"TRUE"
BODY_TYPE"PLUMBING"
CDS_LIB"mstr_standard";
"B \NAC \NWC"1;
"S \NAC"
BN"1"152;
%"TAP"
"6","(900,3600)","2","mstr_standard","I22";
;
HDL_TAP"TRUE"
BODY_TYPE"PLUMBING"
CDS_LIB"mstr_standard";
"B \NAC \NWC"1;
"S \NAC"
BN"2"150;
%"TAP"
"6","(900,3400)","2","mstr_standard","I23";
;
HDL_TAP"TRUE"
BODY_TYPE"PLUMBING"
CDS_LIB"mstr_standard";
"B \NAC \NWC"1;
"S \NAC"
BN"0"154;
%"GND"
"1","(1100,1150)","2","mstr_symbols","I26";
;
HDL_POWER"GND"
ROOM"DDR4_CH_D"
BODY_TYPE"PLUMBING"
CDS_LIB"mstr_symbols"
SIZE"1B"
BOM_COST"MEM"
VOLTAGE"0";
"A\NAC"20;
%"TAP"
"6","(700,5150)","2","mstr_standard","I27";
;
HDL_TAP"TRUE"
BODY_TYPE"PLUMBING"
CDS_LIB"mstr_standard";
"B \NAC \NWC"2;
"S \NAC"
BN"17"176;
%"TAP"
"6","(700,5050)","2","mstr_standard","I28";
;
HDL_TAP"TRUE"
BODY_TYPE"PLUMBING"
CDS_LIB"mstr_standard";
"B \NAC \NWC"2;
"S \NAC"
BN"16"162;
%"TAP"
"6","(700,4750)","2","mstr_standard","I29";
;
HDL_TAP"TRUE"
BODY_TYPE"PLUMBING"
CDS_LIB"mstr_standard";
"B \NAC \NWC"2;
"S \NAC"
BN"13"168;
%"TAP"
"6","(900,5100)","2","mstr_standard","I3";
;
HDL_TAP"TRUE"
BODY_TYPE"PLUMBING"
CDS_LIB"mstr_standard";
"B \NAC \NWC"1;
"S \NAC"
BN"17"161;
%"TAP"
"6","(700,4650)","2","mstr_standard","I30";
;
HDL_TAP"TRUE"
BODY_TYPE"PLUMBING"
CDS_LIB"mstr_standard";
"B \NAC \NWC"2;
"S \NAC"
BN"12"170;
%"TAP"
"6","(700,4550)","2","mstr_standard","I31";
;
HDL_TAP"TRUE"
BODY_TYPE"PLUMBING"
CDS_LIB"mstr_standard";
"B \NAC \NWC"2;
"S \NAC"
BN"11"172;
%"TAP"
"6","(700,4950)","2","mstr_standard","I32";
;
HDL_TAP"TRUE"
BODY_TYPE"PLUMBING"
CDS_LIB"mstr_standard";
"B \NAC \NWC"2;
"S \NAC"
BN"15"164;
%"TAP"
"6","(700,4850)","2","mstr_standard","I33";
;
HDL_TAP"TRUE"
BODY_TYPE"PLUMBING"
CDS_LIB"mstr_standard";
"B \NAC \NWC"2;
"S \NAC"
BN"14"166;
%"TAP"
"6","(-1750,4700)","2","mstr_standard","I35";
;
HDL_TAP"TRUE"
BODY_TYPE"PLUMBING"
CDS_LIB"mstr_standard";
"B \NAC \NWC"4;
"S \NAC"
BN"58"138;
%"TAP"
"6","(-1750,4900)","2","mstr_standard","I36";
;
HDL_TAP"TRUE"
BODY_TYPE"PLUMBING"
CDS_LIB"mstr_standard";
"B \NAC \NWC"4;
"S \NAC"
BN"62"140;
%"TAP"
"6","(-1750,4850)","2","mstr_standard","I37";
;
HDL_TAP"TRUE"
BODY_TYPE"PLUMBING"
CDS_LIB"mstr_standard";
"B \NAC \NWC"4;
"S \NAC"
BN"63"135;
%"TAP"
"6","(-1750,4800)","2","mstr_standard","I38";
;
HDL_TAP"TRUE"
BODY_TYPE"PLUMBING"
CDS_LIB"mstr_standard";
"B \NAC \NWC"4;
"S \NAC"
BN"60"136;
%"TAP"
"6","(-1750,4750)","2","mstr_standard","I39";
;
HDL_TAP"TRUE"
BODY_TYPE"PLUMBING"
CDS_LIB"mstr_standard";
"B \NAC \NWC"4;
"S \NAC"
BN"61"139;
%"TAP"
"6","(900,5000)","2","mstr_standard","I4";
;
HDL_TAP"TRUE"
BODY_TYPE"PLUMBING"
CDS_LIB"mstr_standard";
"B \NAC \NWC"1;
"S \NAC"
BN"16"163;
%"TAP"
"6","(-1750,4450)","2","mstr_standard","I40";
;
HDL_TAP"TRUE"
BODY_TYPE"PLUMBING"
CDS_LIB"mstr_standard";
"B \NAC \NWC"4;
"S \NAC"
BN"55"131;
%"TAP"
"6","(-1750,4600)","2","mstr_standard","I41";
;
HDL_TAP"TRUE"
BODY_TYPE"PLUMBING"
CDS_LIB"mstr_standard";
"B \NAC \NWC"4;
"S \NAC"
BN"56"132;
%"TAP"
"6","(-1750,4650)","2","mstr_standard","I42";
;
HDL_TAP"TRUE"
BODY_TYPE"PLUMBING"
CDS_LIB"mstr_standard";
"B \NAC \NWC"4;
"S \NAC"
BN"59"137;
%"TAP"
"6","(-1750,4500)","2","mstr_standard","I43";
;
HDL_TAP"TRUE"
BODY_TYPE"PLUMBING"
CDS_LIB"mstr_standard";
"B \NAC \NWC"4;
"S \NAC"
BN"54"133;
%"TAP"
"6","(-1750,4550)","2","mstr_standard","I44";
;
HDL_TAP"TRUE"
BODY_TYPE"PLUMBING"
CDS_LIB"mstr_standard";
"B \NAC \NWC"4;
"S \NAC"
BN"57"134;
%"TAP"
"6","(-1750,4200)","2","mstr_standard","I45";
;
HDL_TAP"TRUE"
BODY_TYPE"PLUMBING"
CDS_LIB"mstr_standard";
"B \NAC \NWC"4;
"S \NAC"
BN"48"126;
%"TAP"
"6","(-1750,4400)","2","mstr_standard","I46";
;
HDL_TAP"TRUE"
BODY_TYPE"PLUMBING"
CDS_LIB"mstr_standard";
"B \NAC \NWC"4;
"S \NAC"
BN"52"130;
%"TAP"
"6","(-1750,4350)","2","mstr_standard","I47";
;
HDL_TAP"TRUE"
BODY_TYPE"PLUMBING"
CDS_LIB"mstr_standard";
"B \NAC \NWC"4;
"S \NAC"
BN"53"129;
%"TAP"
"6","(-1750,4250)","2","mstr_standard","I48";
;
HDL_TAP"TRUE"
BODY_TYPE"PLUMBING"
CDS_LIB"mstr_standard";
"B \NAC \NWC"4;
"S \NAC"
BN"51"127;
%"TAP"
"6","(-1750,4300)","2","mstr_standard","I49";
;
HDL_TAP"TRUE"
BODY_TYPE"PLUMBING"
CDS_LIB"mstr_standard";
"B \NAC \NWC"4;
"S \NAC"
BN"50"128;
%"TAP"
"6","(900,4900)","2","mstr_standard","I5";
;
HDL_TAP"TRUE"
BODY_TYPE"PLUMBING"
CDS_LIB"mstr_standard";
"B \NAC \NWC"1;
"S \NAC"
BN"15"165;
%"TAP"
"6","(-1750,4100)","2","mstr_standard","I50";
;
HDL_TAP"TRUE"
BODY_TYPE"PLUMBING"
CDS_LIB"mstr_standard";
"B \NAC \NWC"4;
"S \NAC"
BN"46"124;
%"TAP"
"6","(-1750,4150)","2","mstr_standard","I51";
;
HDL_TAP"TRUE"
BODY_TYPE"PLUMBING"
CDS_LIB"mstr_standard";
"B \NAC \NWC"4;
"S \NAC"
BN"49"125;
%"TAP"
"6","(-1750,4050)","2","mstr_standard","I52";
;
HDL_TAP"TRUE"
BODY_TYPE"PLUMBING"
CDS_LIB"mstr_standard";
"B \NAC \NWC"4;
"S \NAC"
BN"47"106;
%"TAP"
"6","(-1750,3950)","2","mstr_standard","I53";
;
HDL_TAP"TRUE"
BODY_TYPE"PLUMBING"
CDS_LIB"mstr_standard";
"B \NAC \NWC"4;
"S \NAC"
BN"45"104;
%"TAP"
"6","(-1750,4000)","2","mstr_standard","I54";
;
HDL_TAP"TRUE"
BODY_TYPE"PLUMBING"
CDS_LIB"mstr_standard";
"B \NAC \NWC"4;
"S \NAC"
BN"44"105;
%"TAP"
"6","(700,4250)","2","mstr_standard","I55";
;
HDL_TAP"TRUE"
BODY_TYPE"PLUMBING"
CDS_LIB"mstr_standard";
"B \NAC \NWC"2;
"S \NAC"
BN"8"157;
%"TAP"
"6","(700,4150)","2","mstr_standard","I56";
;
HDL_TAP"TRUE"
BODY_TYPE"PLUMBING"
CDS_LIB"mstr_standard";
"B \NAC \NWC"2;
"S \NAC"
BN"7"159;
%"TAP"
"6","(700,4050)","2","mstr_standard","I57";
;
HDL_TAP"TRUE"
BODY_TYPE"PLUMBING"
CDS_LIB"mstr_standard";
"B \NAC \NWC"2;
"S \NAC"
BN"6"141;
%"TAP"
"6","(700,4350)","2","mstr_standard","I58";
;
HDL_TAP"TRUE"
BODY_TYPE"PLUMBING"
CDS_LIB"mstr_standard";
"B \NAC \NWC"2;
"S \NAC"
BN"9"155;
%"TAP"
"6","(700,4450)","2","mstr_standard","I59";
;
HDL_TAP"TRUE"
BODY_TYPE"PLUMBING"
CDS_LIB"mstr_standard";
"B \NAC \NWC"2;
"S \NAC"
BN"10"174;
%"TAP"
"6","(900,4800)","2","mstr_standard","I6";
;
HDL_TAP"TRUE"
BODY_TYPE"PLUMBING"
CDS_LIB"mstr_standard";
"B \NAC \NWC"1;
"S \NAC"
BN"14"167;
%"TAP"
"6","(700,3750)","2","mstr_standard","I60";
;
HDL_TAP"TRUE"
BODY_TYPE"PLUMBING"
CDS_LIB"mstr_standard";
"B \NAC \NWC"2;
"S \NAC"
BN"3"147;
%"TAP"
"6","(700,3550)","2","mstr_standard","I61";
;
HDL_TAP"TRUE"
BODY_TYPE"PLUMBING"
CDS_LIB"mstr_standard";
"B \NAC \NWC"2;
"S \NAC"
BN"1"151;
%"TAP"
"6","(700,3650)","2","mstr_standard","I62";
;
HDL_TAP"TRUE"
BODY_TYPE"PLUMBING"
CDS_LIB"mstr_standard";
"B \NAC \NWC"2;
"S \NAC"
BN"2"149;
%"TAP"
"6","(700,3950)","2","mstr_standard","I63";
;
HDL_TAP"TRUE"
BODY_TYPE"PLUMBING"
CDS_LIB"mstr_standard";
"B \NAC \NWC"2;
"S \NAC"
BN"5"143;
%"TAP"
"6","(700,3850)","2","mstr_standard","I64";
;
HDL_TAP"TRUE"
BODY_TYPE"PLUMBING"
CDS_LIB"mstr_standard";
"B \NAC \NWC"2;
"S \NAC"
BN"4"145;
%"TAP"
"6","(700,3450)","2","mstr_standard","I65";
;
HDL_TAP"TRUE"
BODY_TYPE"PLUMBING"
CDS_LIB"mstr_standard";
"B \NAC \NWC"2;
"S \NAC"
BN"0"153;
%"TAP"
"6","(-1750,3900)","2","mstr_standard","I66";
;
HDL_TAP"TRUE"
BODY_TYPE"PLUMBING"
CDS_LIB"mstr_standard";
"B \NAC \NWC"4;
"S \NAC"
BN"42"103;
%"TAP"
"6","(-1750,3850)","2","mstr_standard","I67";
;
HDL_TAP"TRUE"
BODY_TYPE"PLUMBING"
CDS_LIB"mstr_standard";
"B \NAC \NWC"4;
"S \NAC"
BN"43"102;
%"TAP"
"6","(-1750,3750)","2","mstr_standard","I68";
;
HDL_TAP"TRUE"
BODY_TYPE"PLUMBING"
CDS_LIB"mstr_standard";
"B \NAC \NWC"4;
"S \NAC"
BN"41"100;
%"TAP"
"6","(-1750,3800)","2","mstr_standard","I69";
;
HDL_TAP"TRUE"
BODY_TYPE"PLUMBING"
CDS_LIB"mstr_standard";
"B \NAC \NWC"4;
"S \NAC"
BN"40"101;
%"TAP"
"6","(900,4700)","2","mstr_standard","I7";
;
HDL_TAP"TRUE"
BODY_TYPE"PLUMBING"
CDS_LIB"mstr_standard";
"B \NAC \NWC"1;
"S \NAC"
BN"13"169;
%"TAP"
"6","(-1750,3700)","2","mstr_standard","I70";
;
HDL_TAP"TRUE"
BODY_TYPE"PLUMBING"
CDS_LIB"mstr_standard";
"B \NAC \NWC"4;
"S \NAC"
BN"38"99;
%"TAP"
"6","(-1750,3650)","2","mstr_standard","I71";
;
HDL_TAP"TRUE"
BODY_TYPE"PLUMBING"
CDS_LIB"mstr_standard";
"B \NAC \NWC"4;
"S \NAC"
BN"39"97;
%"TAP"
"6","(-1750,3600)","2","mstr_standard","I72";
;
HDL_TAP"TRUE"
BODY_TYPE"PLUMBING"
CDS_LIB"mstr_standard";
"B \NAC \NWC"4;
"S \NAC"
BN"36"98;
%"TAP"
"6","(-1750,3550)","2","mstr_standard","I73";
;
HDL_TAP"TRUE"
BODY_TYPE"PLUMBING"
CDS_LIB"mstr_standard";
"B \NAC \NWC"4;
"S \NAC"
BN"37"92;
%"TAP"
"6","(-1750,3500)","2","mstr_standard","I74";
;
HDL_TAP"TRUE"
BODY_TYPE"PLUMBING"
CDS_LIB"mstr_standard";
"B \NAC \NWC"4;
"S \NAC"
BN"34"93;
%"TAP"
"6","(-1750,3450)","2","mstr_standard","I75";
;
HDL_TAP"TRUE"
BODY_TYPE"PLUMBING"
CDS_LIB"mstr_standard";
"B \NAC \NWC"4;
"S \NAC"
BN"35"96;
%"TAP"
"6","(-1750,3400)","2","mstr_standard","I76";
;
HDL_TAP"TRUE"
BODY_TYPE"PLUMBING"
CDS_LIB"mstr_standard";
"B \NAC \NWC"4;
"S \NAC"
BN"32"95;
%"TAP"
"6","(-1750,3350)","2","mstr_standard","I77";
;
HDL_TAP"TRUE"
BODY_TYPE"PLUMBING"
CDS_LIB"mstr_standard";
"B \NAC \NWC"4;
"S \NAC"
BN"33"94;
%"TAP"
"6","(-1750,3200)","2","mstr_standard","I78";
;
HDL_TAP"TRUE"
BODY_TYPE"PLUMBING"
CDS_LIB"mstr_standard";
"B \NAC \NWC"4;
"S \NAC"
BN"28"91;
%"TAP"
"6","(-1750,3250)","2","mstr_standard","I79";
;
HDL_TAP"TRUE"
BODY_TYPE"PLUMBING"
CDS_LIB"mstr_standard";
"B \NAC \NWC"4;
"S \NAC"
BN"31"88;
%"TAP"
"6","(900,4600)","2","mstr_standard","I8";
;
HDL_TAP"TRUE"
BODY_TYPE"PLUMBING"
CDS_LIB"mstr_standard";
"B \NAC \NWC"1;
"S \NAC"
BN"12"171;
%"TAP"
"6","(-1750,3300)","2","mstr_standard","I80";
;
HDL_TAP"TRUE"
BODY_TYPE"PLUMBING"
CDS_LIB"mstr_standard";
"B \NAC \NWC"4;
"S \NAC"
BN"30"89;
%"TAP"
"6","(-1750,2900)","2","mstr_standard","I81";
;
HDL_TAP"TRUE"
BODY_TYPE"PLUMBING"
CDS_LIB"mstr_standard";
"B \NAC \NWC"4;
"S \NAC"
BN"22"84;
%"TAP"
"6","(-1750,3100)","2","mstr_standard","I82";
;
HDL_TAP"TRUE"
BODY_TYPE"PLUMBING"
CDS_LIB"mstr_standard";
"B \NAC \NWC"4;
"S \NAC"
BN"26"87;
%"TAP"
"6","(-1750,3150)","2","mstr_standard","I83";
;
HDL_TAP"TRUE"
BODY_TYPE"PLUMBING"
CDS_LIB"mstr_standard";
"B \NAC \NWC"4;
"S \NAC"
BN"29"90;
%"TAP"
"6","(-1750,3050)","2","mstr_standard","I84";
;
HDL_TAP"TRUE"
BODY_TYPE"PLUMBING"
CDS_LIB"mstr_standard";
"B \NAC \NWC"4;
"S \NAC"
BN"27"82;
%"TAP"
"6","(-1750,3000)","2","mstr_standard","I85";
;
HDL_TAP"TRUE"
BODY_TYPE"PLUMBING"
CDS_LIB"mstr_standard";
"B \NAC \NWC"4;
"S \NAC"
BN"24"86;
%"TAP"
"6","(-1750,2950)","2","mstr_standard","I86";
;
HDL_TAP"TRUE"
BODY_TYPE"PLUMBING"
CDS_LIB"mstr_standard";
"B \NAC \NWC"4;
"S \NAC"
BN"25"85;
%"TAP"
"6","(-1750,2650)","2","mstr_standard","I88";
;
HDL_TAP"TRUE"
BODY_TYPE"PLUMBING"
CDS_LIB"mstr_standard";
"B \NAC \NWC"4;
"S \NAC"
BN"19"78;
%"TAP"
"6","(-1750,2850)","2","mstr_standard","I89";
;
HDL_TAP"TRUE"
BODY_TYPE"PLUMBING"
CDS_LIB"mstr_standard";
"B \NAC \NWC"4;
"S \NAC"
BN"23"83;
%"PVTT_KLM"
"1","(-1250,2750)","0","mstr_symbols","I9";
;
HDL_POWER"PVTT_KLM"
ROOM"DDR4_CH_D"
BODY_TYPE"PLUMBING"
CDS_LIB"mstr_symbols"
BOM_COST"MEM"
VOLTAGE"0.6V";
"G\NAC"21;
%"TAP"
"6","(-1750,2800)","2","mstr_standard","I90";
;
HDL_TAP"TRUE"
BODY_TYPE"PLUMBING"
CDS_LIB"mstr_standard";
"B \NAC \NWC"4;
"S \NAC"
BN"20"81;
%"TAP"
"6","(-1750,2700)","2","mstr_standard","I91";
;
HDL_TAP"TRUE"
BODY_TYPE"PLUMBING"
CDS_LIB"mstr_standard";
"B \NAC \NWC"4;
"S \NAC"
BN"18"79;
%"TAP"
"6","(-1750,2750)","2","mstr_standard","I92";
;
HDL_TAP"TRUE"
BODY_TYPE"PLUMBING"
CDS_LIB"mstr_standard";
"B \NAC \NWC"4;
"S \NAC"
BN"21"80;
%"TAP"
"6","(-1750,2400)","2","mstr_standard","I93";
;
HDL_TAP"TRUE"
BODY_TYPE"PLUMBING"
CDS_LIB"mstr_standard";
"B \NAC \NWC"4;
"S \NAC"
BN"12"73;
%"TAP"
"6","(-1750,2550)","2","mstr_standard","I94";
;
HDL_TAP"TRUE"
BODY_TYPE"PLUMBING"
CDS_LIB"mstr_standard";
"B \NAC \NWC"4;
"S \NAC"
BN"17"75;
%"TAP"
"6","(-1750,2600)","2","mstr_standard","I95";
;
HDL_TAP"TRUE"
BODY_TYPE"PLUMBING"
CDS_LIB"mstr_standard";
"B \NAC \NWC"4;
"S \NAC"
BN"16"77;
%"TAP"
"6","(-1750,2450)","2","mstr_standard","I96";
;
HDL_TAP"TRUE"
BODY_TYPE"PLUMBING"
CDS_LIB"mstr_standard";
"B \NAC \NWC"4;
"S \NAC"
BN"15"74;
%"TAP"
"6","(-1750,2500)","2","mstr_standard","I97";
;
HDL_TAP"TRUE"
BODY_TYPE"PLUMBING"
CDS_LIB"mstr_standard";
"B \NAC \NWC"4;
"S \NAC"
BN"14"72;
%"TAP"
"6","(-1750,2150)","2","mstr_standard","I98";
;
HDL_TAP"TRUE"
BODY_TYPE"PLUMBING"
CDS_LIB"mstr_standard";
"B \NAC \NWC"4;
"S \NAC"
BN"9"68;
%"TAP"
"6","(-1750,2250)","2","mstr_standard","I99";
;
HDL_TAP"TRUE"
BODY_TYPE"PLUMBING"
CDS_LIB"mstr_standard";
"B \NAC \NWC"4;
"S \NAC"
BN"11"71;
END.
